(kicad_pcb
	(version 20260206)
	(generator "pcbnew")
	(generator_version "10.0")
	(general
		(thickness 1.6)
		(legacy_teardrops no)
	)
	(paper "A4")
	(title_block
		(title "01162023_DA0F0TEBIF0_F0T_Expander_BD_F_brd_V02_OCP.brd")
		(comment 1 "Grand Teton / footprints 1044-1050 of 9728")
	)
	(layers
		(0 "F.Cu" signal "TOP")
		(4 "In1.Cu" signal "GND")
		(6 "In2.Cu" signal "VCC")
		(8 "In3.Cu" signal "VCC1")
		(10 "In4.Cu" signal "GND1")
		(12 "In5.Cu" signal "IN1")
		(14 "In6.Cu" signal "GND2")
		(16 "In7.Cu" signal "IN2")
		(18 "In8.Cu" signal "GND3")
		(20 "In9.Cu" signal "IN3")
		(22 "In10.Cu" signal "GND4")
		(24 "In11.Cu" signal "IN4")
		(26 "In12.Cu" signal "GND5")
		(28 "In13.Cu" signal "IN5")
		(30 "In14.Cu" signal "GND6")
		(32 "In15.Cu" signal "IN6")
		(34 "In16.Cu" signal "GND7")
		(2 "B.Cu" signal "BOTTOM")
		(9 "F.Adhes" user "F.Adhesive")
		(11 "B.Adhes" user "B.Adhesive")
		(13 "F.Paste" user "Package Geometry/Pastemask Top")
		(15 "B.Paste" user "Package Geometry/Pastemask Bottom")
		(5 "F.SilkS" user "Ref Des/Silkscreen Top")
		(7 "B.SilkS" user "Ref Des/Silkscreen Bottom")
		(1 "F.Mask" user "Board Geometry/Soldermask Top")
		(3 "B.Mask" user "Board Geometry/Soldermask Bottom")
		(17 "Dwgs.User" user "User.Drawings")
		(19 "Cmts.User" user "User.Comments")
		(21 "Eco1.User" user "User.Eco1")
		(23 "Eco2.User" user "User.Eco2")
		(25 "Edge.Cuts" user "Board Geometry/Outline")
		(27 "Margin" user)
		(31 "F.CrtYd" user "Package Geometry/Place Bound Top")
		(29 "B.CrtYd" user "Package Geometry/Place Bound Bottom")
		(35 "F.Fab" user "Ref Des/Assembly Top")
		(33 "B.Fab" user "Ref Des/Assembly Bottom")
	)
	(footprint ""
		(layer "F.Cu")
		(at 460.508858 -308.21884 -90)
		(property "Reference" "PC981"
			(at 0 0 270)
			(layer "F.SilkS")
			(hide yes)
			(effects
				(font
					(size 1.27 1.27)
				)
			)
		)
		(property "Value" ""
			(at 0 0 270)
			(layer "F.Fab")
			(effects
				(font
					(size 1.27 1.27)
				)
			)
		)
		(duplicate_pad_numbers_are_jumpers no)
		(fp_line
			(start -0.7874 0.4064)
			(end -0.7874 -0.4064)
			(stroke
				(width 0.1524)
				(type default)
			)
			(layer "F.SilkS")
		)
		(fp_line
			(start 0.7874 0.4064)
			(end -0.7874 0.4064)
			(stroke
				(width 0.1524)
				(type default)
			)
			(layer "F.SilkS")
		)
		(fp_line
			(start -0.7874 -0.4064)
			(end 0.7874 -0.4064)
			(stroke
				(width 0.1524)
				(type default)
			)
			(layer "F.SilkS")
		)
		(fp_line
			(start 0.7874 -0.4064)
			(end 0.7874 0.4064)
			(stroke
				(width 0.1524)
				(type default)
			)
			(layer "F.SilkS")
		)
		(fp_line
			(start -0.67945 0.3048)
			(end -0.67945 -0.305054)
			(stroke
				(width 0.1)
				(type default)
			)
			(layer "F.Fab")
		)
		(fp_line
			(start -0.12065 0.3048)
			(end -0.67945 0.3048)
			(stroke
				(width 0.1)
				(type default)
			)
			(layer "F.Fab")
		)
		(fp_line
			(start 0.120396 0.3048)
			(end 0.120396 0.2794)
			(stroke
				(width 0.1)
				(type default)
			)
			(layer "F.Fab")
		)
		(fp_line
			(start 0.67945 0.3048)
			(end 0.120396 0.3048)
			(stroke
				(width 0.1)
				(type default)
			)
			(layer "F.Fab")
		)
		(fp_line
			(start -0.12065 0.2794)
			(end -0.12065 0.3048)
			(stroke
				(width 0.1)
				(type default)
			)
			(layer "F.Fab")
		)
		(fp_line
			(start 0.120396 0.2794)
			(end -0.12065 0.2794)
			(stroke
				(width 0.1)
				(type default)
			)
			(layer "F.Fab")
		)
		(fp_line
			(start -0.12065 -0.2794)
			(end 0.12065 -0.2794)
			(stroke
				(width 0.1)
				(type default)
			)
			(layer "F.Fab")
		)
		(fp_line
			(start 0.12065 -0.2794)
			(end 0.12065 -0.3048)
			(stroke
				(width 0.1)
				(type default)
			)
			(layer "F.Fab")
		)
		(fp_line
			(start 0.12065 -0.3048)
			(end 0.67945 -0.3048)
			(stroke
				(width 0.1)
				(type default)
			)
			(layer "F.Fab")
		)
		(fp_line
			(start 0.67945 -0.3048)
			(end 0.67945 0.3048)
			(stroke
				(width 0.1)
				(type default)
			)
			(layer "F.Fab")
		)
		(fp_line
			(start -0.67945 -0.305054)
			(end -0.12065 -0.305054)
			(stroke
				(width 0.1)
				(type default)
			)
			(layer "F.Fab")
		)
		(fp_line
			(start -0.12065 -0.305054)
			(end -0.12065 -0.2794)
			(stroke
				(width 0.1)
				(type default)
			)
			(layer "F.Fab")
		)
		(pad "1" smd circle
			(at -0.40005 0 270)
			(size 0 0)
			(layers "F.Cu" "F.Mask" "F.Paste")
			(net "SH_P1V25_PEX3_FB_P")
		)
		(pad "2" smd circle
			(at 0.40005 0 270)
			(size 0 0)
			(layers "F.Cu" "F.Mask" "F.Paste")
			(net "SH_P1V25_PEX3_FB_N")
		)
	)
	(footprint ""
		(layer "F.Cu")
		(at 265.487658 -282.018232)
		(property "Reference" "C3415"
			(at 0 0 0)
			(layer "F.SilkS")
			(hide yes)
			(effects
				(font
					(size 1.27 1.27)
				)
			)
		)
		(property "Value" ""
			(at 0 0 0)
			(layer "F.Fab")
			(effects
				(font
					(size 1.27 1.27)
				)
			)
		)
		(duplicate_pad_numbers_are_jumpers no)
		(fp_line
			(start -1.2954 -0.5842)
			(end 1.2954 -0.5842)
			(stroke
				(width 0.1524)
				(type default)
			)
			(layer "F.SilkS")
		)
		(fp_line
			(start -1.2954 0.5842)
			(end -1.2954 -0.5842)
			(stroke
				(width 0.1524)
				(type default)
			)
			(layer "F.SilkS")
		)
		(fp_line
			(start 1.2954 -0.5842)
			(end 1.2954 0.5842)
			(stroke
				(width 0.1524)
				(type default)
			)
			(layer "F.SilkS")
		)
		(fp_line
			(start 1.2954 0.5842)
			(end -1.2954 0.5842)
			(stroke
				(width 0.1524)
				(type default)
			)
			(layer "F.SilkS")
		)
		(fp_line
			(start -1.1938 -0.4064)
			(end -0.8636 -0.4064)
			(stroke
				(width 0.1)
				(type default)
			)
			(layer "F.Fab")
		)
		(fp_line
			(start -1.1938 0.4064)
			(end -1.1938 -0.4064)
			(stroke
				(width 0.1)
				(type default)
			)
			(layer "F.Fab")
		)
		(fp_line
			(start -0.8636 -0.4572)
			(end 0.8636 -0.4572)
			(stroke
				(width 0.1)
				(type default)
			)
			(layer "F.Fab")
		)
		(fp_line
			(start -0.8636 -0.4064)
			(end -0.8636 -0.4572)
			(stroke
				(width 0.1)
				(type default)
			)
			(layer "F.Fab")
		)
		(fp_line
			(start -0.8636 0.4064)
			(end -1.1938 0.4064)
			(stroke
				(width 0.1)
				(type default)
			)
			(layer "F.Fab")
		)
		(fp_line
			(start -0.8636 0.4572)
			(end -0.8636 0.4064)
			(stroke
				(width 0.1)
				(type default)
			)
			(layer "F.Fab")
		)
		(fp_line
			(start 0.8636 -0.4572)
			(end 0.8636 -0.4064)
			(stroke
				(width 0.1)
				(type default)
			)
			(layer "F.Fab")
		)
		(fp_line
			(start 0.8636 -0.4064)
			(end 1.1938 -0.4064)
			(stroke
				(width 0.1)
				(type default)
			)
			(layer "F.Fab")
		)
		(fp_line
			(start 0.8636 0.4064)
			(end 0.8636 0.4572)
			(stroke
				(width 0.1)
				(type default)
			)
			(layer "F.Fab")
		)
		(fp_line
			(start 0.8636 0.4572)
			(end -0.8636 0.4572)
			(stroke
				(width 0.1)
				(type default)
			)
			(layer "F.Fab")
		)
		(fp_line
			(start 1.1938 -0.4064)
			(end 1.1938 0.4064)
			(stroke
				(width 0.1)
				(type default)
			)
			(layer "F.Fab")
		)
		(fp_line
			(start 1.1938 0.4064)
			(end 0.8636 0.4064)
			(stroke
				(width 0.1)
				(type default)
			)
			(layer "F.Fab")
		)
		(pad "1" smd rect
			(at -0.7366 0 270)
			(size 0.7112 0.8128)
			(layers "F.Cu" "F.Mask" "F.Paste")
			(net "SYSPLL_VDDA18_PEX2")
		)
		(pad "2" smd rect
			(at 0.7366 0 270)
			(size 0.7112 0.8128)
			(layers "F.Cu" "F.Mask" "F.Paste")
			(net "GND")
		)
	)
	(footprint ""
		(layer "F.Cu")
		(at 431.889408 -63.56223)
		(property "Reference" "Q211"
			(at 0.384302 -2.492756 0)
			(unlocked yes)
			(layer "F.SilkS")
			(effects
				(font
					(size 0.7874 0.5842)
					(thickness 0.1524)
				)
			)
		)
		(property "Value" ""
			(at 0 0 0)
			(layer "F.Fab")
			(effects
				(font
					(size 1.27 1.27)
				)
			)
		)
		(duplicate_pad_numbers_are_jumpers no)
		(fp_line
			(start -1.376172 -1.199896)
			(end -0.508 -1.199896)
			(stroke
				(width 0.1524)
				(type default)
			)
			(layer "F.SilkS")
		)
		(fp_line
			(start -1.376172 1.199896)
			(end -1.376172 -1.199896)
			(stroke
				(width 0.1524)
				(type default)
			)
			(layer "F.SilkS")
		)
		(fp_line
			(start -0.508 -1.199896)
			(end 0 -0.762)
			(stroke
				(width 0.1524)
				(type default)
			)
			(layer "F.SilkS")
		)
		(fp_line
			(start 0 -0.762)
			(end 0.508 -1.199896)
			(stroke
				(width 0.1524)
				(type default)
			)
			(layer "F.SilkS")
		)
		(fp_line
			(start 0.508 -1.199896)
			(end 1.376172 -1.199896)
			(stroke
				(width 0.1524)
				(type default)
			)
			(layer "F.SilkS")
		)
		(fp_line
			(start 1.376172 -1.199896)
			(end 1.376172 1.199896)
			(stroke
				(width 0.1524)
				(type default)
			)
			(layer "F.SilkS")
		)
		(fp_line
			(start 1.376172 1.199896)
			(end -1.376172 1.199896)
			(stroke
				(width 0.1524)
				(type default)
			)
			(layer "F.SilkS")
		)
		(fp_poly
			(pts
				(xy -1.561846 -1.107948) (xy -1.83134 -1.916176) (xy -2.370074 -1.377442)
			)
			(stroke
				(width 0)
				(type default)
			)
			(fill yes)
			(layer "F.SilkS")
		)
		(fp_line
			(start -0.674878 -1.100074)
			(end 0.674878 -1.100074)
			(stroke
				(width 0.1)
				(type default)
			)
			(layer "F.Fab")
		)
		(fp_line
			(start -0.674878 1.100074)
			(end -0.674878 -1.100074)
			(stroke
				(width 0.1)
				(type default)
			)
			(layer "F.Fab")
		)
		(fp_line
			(start 0.674878 -1.100074)
			(end 0.674878 1.100074)
			(stroke
				(width 0.1)
				(type default)
			)
			(layer "F.Fab")
		)
		(fp_line
			(start 0.674878 1.100074)
			(end -0.674878 1.100074)
			(stroke
				(width 0.1)
				(type default)
			)
			(layer "F.Fab")
		)
		(fp_poly
			(pts
				(xy -1.4605 -0.7493) (xy -2.2225 -1.1303) (xy -2.2225 -0.3683)
			)
			(stroke
				(width 0)
				(type default)
			)
			(fill yes)
			(layer "F.Fab")
		)
		(pad "1" smd rect
			(at -0.899922 -0.750062 270)
			(size 0.6096 0.6096)
			(layers "F.Cu" "F.Mask" "F.Paste")
			(net "GND")
		)
		(pad "2" smd rect
			(at -0.899922 0 270)
			(size 0.4064 0.6096)
			(layers "F.Cu" "F.Mask" "F.Paste")
			(net "P12V_SSD15_PG_G1")
		)
		(pad "3" smd rect
			(at -0.899922 0.750062 270)
			(size 0.6096 0.6096)
			(layers "F.Cu" "F.Mask" "F.Paste")
			(net "PWRGD_P12V_SSD15_D")
		)
		(pad "4" smd rect
			(at 0.899922 0.750062 270)
			(size 0.6096 0.6096)
			(layers "F.Cu" "F.Mask" "F.Paste")
			(net "GND")
		)
		(pad "5" smd rect
			(at 0.899922 0 270)
			(size 0.4064 0.6096)
			(layers "F.Cu" "F.Mask" "F.Paste")
			(net "P12V_SSD15_PG_G2")
		)
		(pad "6" smd rect
			(at 0.899922 -0.750062 270)
			(size 0.6096 0.6096)
			(layers "F.Cu" "F.Mask" "F.Paste")
			(net "P12V_SSD15_PG_G2")
		)
	)
	(footprint ""
		(layer "F.Cu")
		(at 460.524098 -530.228048)
		(property "Reference" "SCREW_8"
			(at -0.5842 -1.31953 0)
			(unlocked yes)
			(layer "B.SilkS")
			(effects
				(font
					(size 0.7874 0.5842)
					(thickness 0.1524)
				)
				(justify left mirror)
			)
		)
		(property "Value" ""
			(at 0 0 0)
			(layer "F.Fab")
			(effects
				(font
					(size 1.27 1.27)
				)
			)
		)
		(duplicate_pad_numbers_are_jumpers no)
		(pad "1" thru_hole circle
			(at 0 0)
			(size 0.4572 0.4572)
			(drill 0.2032)
			(layers "*.Cu" "*.Mask")
			(remove_unused_layers no)
			(net "Net_9293")
			(clearance 0.127)
			(thermal_gap 0.127)
			(padstack
				(mode front_inner_back)
				(layer "Inner"
					(shape circle)
					(size 0.4572 0.4572)
					(clearance 0.127)
				)
				(layer "B.Cu"
					(shape circle)
					(size 0.508 0.508)
					(clearance 0.1016)
				)
			)
		)
	)
	(footprint ""
		(layer "F.Cu")
		(at 322.221098 -298.87291 -90)
		(property "Reference" "R4018"
			(at 0 0 270)
			(layer "F.SilkS")
			(hide yes)
			(effects
				(font
					(size 1.27 1.27)
				)
			)
		)
		(property "Value" ""
			(at 0 0 270)
			(layer "F.Fab")
			(effects
				(font
					(size 1.27 1.27)
				)
			)
		)
		(duplicate_pad_numbers_are_jumpers no)
		(fp_line
			(start -0.7874 0.4064)
			(end -0.7874 -0.4064)
			(stroke
				(width 0.1524)
				(type default)
			)
			(layer "F.SilkS")
		)
		(fp_line
			(start 0.7874 0.4064)
			(end -0.7874 0.4064)
			(stroke
				(width 0.1524)
				(type default)
			)
			(layer "F.SilkS")
		)
		(fp_line
			(start -0.7874 -0.4064)
			(end 0.7874 -0.4064)
			(stroke
				(width 0.1524)
				(type default)
			)
			(layer "F.SilkS")
		)
		(fp_line
			(start 0.7874 -0.4064)
			(end 0.7874 0.4064)
			(stroke
				(width 0.1524)
				(type default)
			)
			(layer "F.SilkS")
		)
		(fp_line
			(start -0.67945 0.3048)
			(end -0.67945 -0.305054)
			(stroke
				(width 0.1)
				(type default)
			)
			(layer "F.Fab")
		)
		(fp_line
			(start -0.12065 0.3048)
			(end -0.67945 0.3048)
			(stroke
				(width 0.1)
				(type default)
			)
			(layer "F.Fab")
		)
		(fp_line
			(start 0.120396 0.3048)
			(end 0.120396 0.2794)
			(stroke
				(width 0.1)
				(type default)
			)
			(layer "F.Fab")
		)
		(fp_line
			(start 0.67945 0.3048)
			(end 0.120396 0.3048)
			(stroke
				(width 0.1)
				(type default)
			)
			(layer "F.Fab")
		)
		(fp_line
			(start -0.12065 0.2794)
			(end -0.12065 0.3048)
			(stroke
				(width 0.1)
				(type default)
			)
			(layer "F.Fab")
		)
		(fp_line
			(start 0.120396 0.2794)
			(end -0.12065 0.2794)
			(stroke
				(width 0.1)
				(type default)
			)
			(layer "F.Fab")
		)
		(fp_line
			(start -0.12065 -0.2794)
			(end 0.12065 -0.2794)
			(stroke
				(width 0.1)
				(type default)
			)
			(layer "F.Fab")
		)
		(fp_line
			(start 0.12065 -0.2794)
			(end 0.12065 -0.3048)
			(stroke
				(width 0.1)
				(type default)
			)
			(layer "F.Fab")
		)
		(fp_line
			(start 0.12065 -0.3048)
			(end 0.67945 -0.3048)
			(stroke
				(width 0.1)
				(type default)
			)
			(layer "F.Fab")
		)
		(fp_line
			(start 0.67945 -0.3048)
			(end 0.67945 0.3048)
			(stroke
				(width 0.1)
				(type default)
			)
			(layer "F.Fab")
		)
		(fp_line
			(start -0.67945 -0.305054)
			(end -0.12065 -0.305054)
			(stroke
				(width 0.1)
				(type default)
			)
			(layer "F.Fab")
		)
		(fp_line
			(start -0.12065 -0.305054)
			(end -0.12065 -0.2794)
			(stroke
				(width 0.1)
				(type default)
			)
			(layer "F.Fab")
		)
		(pad "1" smd circle
			(at -0.40005 0 270)
			(size 0 0)
			(layers "F.Cu" "F.Mask" "F.Paste")
			(net "P1V8_PEX")
		)
		(pad "2" smd circle
			(at 0.40005 0 270)
			(size 0 0)
			(layers "F.Cu" "F.Mask" "F.Paste")
			(net "I2C_PEX2_HOST_R_SDA")
		)
	)
	(footprint ""
		(layer "F.Cu")
		(at 348.88424 -29.222954 -90)
		(property "Reference" "PC948"
			(at 0 0 270)
			(layer "F.SilkS")
			(hide yes)
			(effects
				(font
					(size 1.27 1.27)
				)
			)
		)
		(property "Value" ""
			(at 0 0 270)
			(layer "F.Fab")
			(effects
				(font
					(size 1.27 1.27)
				)
			)
		)
		(duplicate_pad_numbers_are_jumpers no)
		(fp_line
			(start -0.7874 0.4064)
			(end -0.7874 -0.4064)
			(stroke
				(width 0.1524)
				(type default)
			)
			(layer "F.SilkS")
		)
		(fp_line
			(start 0.7874 0.4064)
			(end -0.7874 0.4064)
			(stroke
				(width 0.1524)
				(type default)
			)
			(layer "F.SilkS")
		)
		(fp_line
			(start -0.7874 -0.4064)
			(end 0.7874 -0.4064)
			(stroke
				(width 0.1524)
				(type default)
			)
			(layer "F.SilkS")
		)
		(fp_line
			(start 0.7874 -0.4064)
			(end 0.7874 0.4064)
			(stroke
				(width 0.1524)
				(type default)
			)
			(layer "F.SilkS")
		)
		(fp_line
			(start -0.67945 0.3048)
			(end -0.67945 -0.305054)
			(stroke
				(width 0.1)
				(type default)
			)
			(layer "F.Fab")
		)
		(fp_line
			(start -0.12065 0.3048)
			(end -0.67945 0.3048)
			(stroke
				(width 0.1)
				(type default)
			)
			(layer "F.Fab")
		)
		(fp_line
			(start 0.120396 0.3048)
			(end 0.120396 0.2794)
			(stroke
				(width 0.1)
				(type default)
			)
			(layer "F.Fab")
		)
		(fp_line
			(start 0.67945 0.3048)
			(end 0.120396 0.3048)
			(stroke
				(width 0.1)
				(type default)
			)
			(layer "F.Fab")
		)
		(fp_line
			(start -0.12065 0.2794)
			(end -0.12065 0.3048)
			(stroke
				(width 0.1)
				(type default)
			)
			(layer "F.Fab")
		)
		(fp_line
			(start 0.120396 0.2794)
			(end -0.12065 0.2794)
			(stroke
				(width 0.1)
				(type default)
			)
			(layer "F.Fab")
		)
		(fp_line
			(start -0.12065 -0.2794)
			(end 0.12065 -0.2794)
			(stroke
				(width 0.1)
				(type default)
			)
			(layer "F.Fab")
		)
		(fp_line
			(start 0.12065 -0.2794)
			(end 0.12065 -0.3048)
			(stroke
				(width 0.1)
				(type default)
			)
			(layer "F.Fab")
		)
		(fp_line
			(start 0.12065 -0.3048)
			(end 0.67945 -0.3048)
			(stroke
				(width 0.1)
				(type default)
			)
			(layer "F.Fab")
		)
		(fp_line
			(start 0.67945 -0.3048)
			(end 0.67945 0.3048)
			(stroke
				(width 0.1)
				(type default)
			)
			(layer "F.Fab")
		)
		(fp_line
			(start -0.67945 -0.305054)
			(end -0.12065 -0.305054)
			(stroke
				(width 0.1)
				(type default)
			)
			(layer "F.Fab")
		)
		(fp_line
			(start -0.12065 -0.305054)
			(end -0.12065 -0.2794)
			(stroke
				(width 0.1)
				(type default)
			)
			(layer "F.Fab")
		)
		(pad "1" smd circle
			(at -0.40005 0 270)
			(size 0 0)
			(layers "F.Cu" "F.Mask" "F.Paste")
			(net "P3V3_AUX")
		)
		(pad "2" smd circle
			(at 0.40005 0 270)
			(size 0 0)
			(layers "F.Cu" "F.Mask" "F.Paste")
			(net "GND")
		)
	)
	(footprint ""
		(layer "F.Cu")
		(at 246.870728 -112.139476 -90)
		(property "Reference" "PR7100"
			(at 0 0 270)
			(layer "F.SilkS")
			(hide yes)
			(effects
				(font
					(size 1.27 1.27)
				)
			)
		)
		(property "Value" ""
			(at 0 0 270)
			(layer "F.Fab")
			(effects
				(font
					(size 1.27 1.27)
				)
			)
		)
		(duplicate_pad_numbers_are_jumpers no)
		(fp_line
			(start -0.7874 0.4064)
			(end -0.7874 -0.4064)
			(stroke
				(width 0.1524)
				(type default)
			)
			(layer "F.SilkS")
		)
		(fp_line
			(start 0.7874 0.4064)
			(end -0.7874 0.4064)
			(stroke
				(width 0.1524)
				(type default)
			)
			(layer "F.SilkS")
		)
		(fp_line
			(start -0.7874 -0.4064)
			(end 0.7874 -0.4064)
			(stroke
				(width 0.1524)
				(type default)
			)
			(layer "F.SilkS")
		)
		(fp_line
			(start 0.7874 -0.4064)
			(end 0.7874 0.4064)
			(stroke
				(width 0.1524)
				(type default)
			)
			(layer "F.SilkS")
		)
		(fp_line
			(start -0.67945 0.3048)
			(end -0.67945 -0.305054)
			(stroke
				(width 0.1)
				(type default)
			)
			(layer "F.Fab")
		)
		(fp_line
			(start -0.12065 0.3048)
			(end -0.67945 0.3048)
			(stroke
				(width 0.1)
				(type default)
			)
			(layer "F.Fab")
		)
		(fp_line
			(start 0.120396 0.3048)
			(end 0.120396 0.2794)
			(stroke
				(width 0.1)
				(type default)
			)
			(layer "F.Fab")
		)
		(fp_line
			(start 0.67945 0.3048)
			(end 0.120396 0.3048)
			(stroke
				(width 0.1)
				(type default)
			)
			(layer "F.Fab")
		)
		(fp_line
			(start -0.12065 0.2794)
			(end -0.12065 0.3048)
			(stroke
				(width 0.1)
				(type default)
			)
			(layer "F.Fab")
		)
		(fp_line
			(start 0.120396 0.2794)
			(end -0.12065 0.2794)
			(stroke
				(width 0.1)
				(type default)
			)
			(layer "F.Fab")
		)
		(fp_line
			(start -0.12065 -0.2794)
			(end 0.12065 -0.2794)
			(stroke
				(width 0.1)
				(type default)
			)
			(layer "F.Fab")
		)
		(fp_line
			(start 0.12065 -0.2794)
			(end 0.12065 -0.3048)
			(stroke
				(width 0.1)
				(type default)
			)
			(layer "F.Fab")
		)
		(fp_line
			(start 0.12065 -0.3048)
			(end 0.67945 -0.3048)
			(stroke
				(width 0.1)
				(type default)
			)
			(layer "F.Fab")
		)
		(fp_line
			(start 0.67945 -0.3048)
			(end 0.67945 0.3048)
			(stroke
				(width 0.1)
				(type default)
			)
			(layer "F.Fab")
		)
		(fp_line
			(start -0.67945 -0.305054)
			(end -0.12065 -0.305054)
			(stroke
				(width 0.1)
				(type default)
			)
			(layer "F.Fab")
		)
		(fp_line
			(start -0.12065 -0.305054)
			(end -0.12065 -0.2794)
			(stroke
				(width 0.1)
				(type default)
			)
			(layer "F.Fab")
		)
		(pad "1" smd circle
			(at -0.40005 0 270)
			(size 0 0)
			(layers "F.Cu" "F.Mask" "F.Paste")
			(net "P3V3_NIC4_CO_ILIMIT")
		)
		(pad "2" smd circle
			(at 0.40005 0 270)
			(size 0 0)
			(layers "F.Cu" "F.Mask" "F.Paste")
			(net "GND")
		)
	)
)
